FILE_TYPE=LIBRARY_PARTS;
primitive 'SS15P3SM386A';
  pin
    'ANODE_1':
      PIN_NUMBER='(1)';
      INPUT_LOAD='(-0.01,0.01)';
    'CATHODE':
      PIN_NUMBER='(K)';
      OUTPUT_LOAD='(1.0,-1.0)';
    'ANODE_2':
      PIN_NUMBER='(2)';
      INPUT_LOAD='(-0.01,0.01)';
  end_pin;
  body
    PART_NAME='SS15P3SM386A';
    BODY_NAME='SS15P3SM386A';
    PHYS_DES_PREFIX='D';
    CLASS='DISCRETE';
  end_body;
end_primitive;

END.
